(kicad_pcb
	(version 20241229)
	(generator "pcbnew")
	(generator_version "9.0")
	(general
		(thickness 1.6296)
		(legacy_teardrops no)
	)
	(paper "A3")
	(title_block
		(title "Thunderbolt to 10GbE adapter")
		(date "2026-04-21")
		(rev "1.1.0")
		(company "Antmicro Ltd")
		(comment 1 "www.antmicro.com")
		(comment 9 "footprint 290 of 703 (U3), pads 75-96 of 96")
	)
	(layers
		(0 "F.Cu" signal)
		(4 "In1.Cu" signal)
		(6 "In2.Cu" signal)
		(8 "In3.Cu" signal)
		(10 "In4.Cu" signal)
		(12 "In5.Cu" signal)
		(14 "In6.Cu" signal)
		(2 "B.Cu" signal)
		(9 "F.Adhes" user "F.Adhesive")
		(11 "B.Adhes" user "B.Adhesive")
		(13 "F.Paste" user)
		(15 "B.Paste" user)
		(5 "F.SilkS" user "F.Silkscreen")
		(7 "B.SilkS" user "B.Silkscreen")
		(1 "F.Mask" user)
		(3 "B.Mask" user)
		(17 "Dwgs.User" user "User.Drawings")
		(19 "Cmts.User" user "User.Comments")
		(21 "Eco1.User" user "User.Eco1")
		(23 "Eco2.User" user "User.Eco2")
		(25 "Edge.Cuts" user)
		(27 "Margin" user)
		(31 "F.CrtYd" user "F.Courtyard")
		(29 "B.CrtYd" user "B.Courtyard")
		(35 "F.Fab" user)
		(33 "B.Fab" user)
	)
	(footprint "antmicro-footprints:IC_TPS65983BAZBHR"
		(layer "F.Cu")
		(at 135 136.5 -90)
		(property "Reference" "U3"
			(at -3.7 2.8 0)
			(unlocked yes)
			(layer "F.SilkS")
			(effects
				(font
					(size 0.7 0.7)
					(thickness 0.15)
				)
			)
		)
		(property "Value" "TPS65983BAZBHR"
			(at 0 4.1 270)
			(unlocked yes)
			(layer "F.Fab")
			(effects
				(font
					(size 0.7 0.7)
					(thickness 0.15)
				)
			)
		)
		(property "Datasheet" "https://www.ti.com/lit/ds/symlink/tps65983b.pdf?ts=1678712702533&ref_url=https%253A%252F%252Fwww.ti.com%252Fproduct%252FTPS65983B"
			(at 0 0 270)
			(layer "F.Fab")
			(hide yes)
			(effects
				(font
					(size 1.27 1.27)
					(thickness 0.15)
				)
			)
		)
		(property "Description" "USB Interface IC Universal USB Type-C and Power Delivery (PD) 3.0 controller 96-NFBGA -10°C to 85"
			(at 0 0 270)
			(layer "F.Fab")
			(hide yes)
			(effects
				(font
					(size 1.27 1.27)
					(thickness 0.15)
				)
			)
		)
		(property "MPN" "TPS65983BAZBHR"
			(at 0 0 270)
			(unlocked yes)
			(layer "F.Fab")
			(hide yes)
			(effects
				(font
					(size 1 1)
					(thickness 0.15)
				)
			)
		)
		(property "Manufacturer" "Texas Instruments"
			(at 0 0 270)
			(unlocked yes)
			(layer "F.Fab")
			(hide yes)
			(effects
				(font
					(size 1 1)
					(thickness 0.15)
				)
			)
		)
		(property "License" "Apache-2.0"
			(at 0 0 270)
			(unlocked yes)
			(layer "F.Fab")
			(hide yes)
			(effects
				(font
					(size 1 1)
					(thickness 0.15)
				)
			)
		)
		(property "Author" "Antmicro"
			(at 0 0 270)
			(unlocked yes)
			(layer "F.Fab")
			(hide yes)
			(effects
				(font
					(size 1 1)
					(thickness 0.15)
				)
			)
		)
		(sheetname "/PD and TB DC-DC/")
		(sheetfile "PD_and_TB_DC_DC.kicad_sch")
		(attr smd)
		(pad "K1" smd oval
			(at -2.5 2 270)
			(size 0.25 0.17)
			(layers "F.Cu" "F.Mask" "F.Paste")
			(net 172 "Net-(U3-LDO_1V8A)")
			(pinfunction "LDO_1V8A")
			(pintype "power_out")
			(solder_paste_margin_ratio 0)
		)
		(pad "K2" smd circle
			(at -2 2 180)
			(size 0.25 0.25)
			(layers "F.Cu" "F.Mask")
			(net 23 "GND")
			(pinfunction "DEBUG2(GPIO14,HD3POL)")
			(pintype "bidirectional")
			(solder_paste_margin_ratio 0)
		)
		(pad "K3" smd circle
			(at -1.5 2 180)
			(size 0.25 0.25)
			(layers "F.Cu" "F.Mask")
			(net 23 "GND")
			(pinfunction "DEBUG4(GPIO12,CONFIG2)")
			(pintype "bidirectional")
			(solder_paste_margin_ratio 0)
		)
		(pad "K4" smd circle
			(at -1 2 180)
			(size 0.25 0.25)
			(layers "F.Cu" "F.Mask")
			(net 376 "/PD and TB DC-DC/LSX_1.LSX_P2R")
			(pinfunction "LSX_P2R")
			(pintype "output")
			(solder_paste_margin_ratio 0)
		)
		(pad "K5" smd circle
			(at -0.5 2 180)
			(size 0.25 0.25)
			(layers "F.Cu" "F.Mask")
			(net 395 "/PD and TB DC-DC/USB_RP.D-")
			(pinfunction "USB_RP_N")
			(pintype "bidirectional")
			(solder_paste_margin_ratio 0)
		)
		(pad "K6" smd circle
			(at 0 2 180)
			(size 0.25 0.25)
			(layers "F.Cu" "F.Mask")
			(net 368 "/PD and TB DC-DC/USB3.D_A_P")
			(pinfunction "C_USB_TP")
			(pintype "bidirectional")
			(solder_paste_margin_ratio 0)
		)
		(pad "K7" smd circle
			(at 0.5 2 180)
			(size 0.25 0.25)
			(layers "F.Cu" "F.Mask")
			(net 365 "/PD and TB DC-DC/USB3.D_B_P")
			(pinfunction "C_USB_BP")
			(pintype "bidirectional")
			(solder_paste_margin_ratio 0)
		)
		(pad "K8" smd circle
			(at 1 2 180)
			(size 0.25 0.25)
			(layers "F.Cu" "F.Mask")
			(net 369 "/PD and TB DC-DC/USB3.SBU1")
			(pinfunction "C_SBU1")
			(pintype "bidirectional")
			(solder_paste_margin_ratio 0)
		)
		(pad "K9" smd circle
			(at 1.5 2 180)
			(size 0.25 0.25)
			(layers "F.Cu" "F.Mask")
			(net 23 "GND")
			(pinfunction "RPD_G1")
			(pintype "bidirectional")
			(solder_paste_margin_ratio 0)
		)
		(pad "K10" smd circle
			(at 2 2 180)
			(size 0.25 0.25)
			(layers "F.Cu" "F.Mask")
			(net 23 "GND")
			(pinfunction "RPD_G2")
			(pintype "bidirectional")
			(solder_paste_margin_ratio 0)
		)
		(pad "K11" smd oval
			(at 2.5 2 270)
			(size 0.25 0.17)
			(layers "F.Cu" "F.Mask" "F.Paste")
			(net 182 "VBUS")
			(pinfunction "VBUS")
			(pintype "power_in")
			(solder_paste_margin_ratio 0)
		)
		(pad "L1" smd circle
			(at -2.5 2.5 180)
			(size 0.25 0.25)
			(layers "F.Cu" "F.Mask")
			(net 23 "GND")
			(pinfunction "GND")
			(pintype "power_in")
			(solder_paste_margin_ratio 0)
		)
		(pad "L2" smd oval
			(at -2 2.5 270)
			(size 0.17 0.25)
			(layers "F.Cu" "F.Mask" "F.Paste")
			(net 23 "GND")
			(pinfunction "DEBUG1(GPIO15)")
			(pintype "bidirectional")
			(solder_paste_margin_ratio 0)
		)
		(pad "L3" smd oval
			(at -1.5 2.5 270)
			(size 0.17 0.25)
			(layers "F.Cu" "F.Mask" "F.Paste")
			(net 23 "GND")
			(pinfunction "DEBUG3(GPIO13,CONFIG1)")
			(pintype "bidirectional")
			(solder_paste_margin_ratio 0)
		)
		(pad "L4" smd oval
			(at -1 2.5 270)
			(size 0.17 0.25)
			(layers "F.Cu" "F.Mask" "F.Paste")
			(net 383 "/PD and TB DC-DC/LSX_1.LSX_R2P")
			(pinfunction "LSX_R2P")
			(pintype "input")
			(solder_paste_margin_ratio 0)
		)
		(pad "L5" smd oval
			(at -0.5 2.5 270)
			(size 0.17 0.25)
			(layers "F.Cu" "F.Mask" "F.Paste")
			(net 396 "/PD and TB DC-DC/USB_RP.D+")
			(pinfunction "USB_RP_P")
			(pintype "bidirectional")
			(solder_paste_margin_ratio 0)
		)
		(pad "L6" smd oval
			(at 0 2.5 270)
			(size 0.17 0.25)
			(layers "F.Cu" "F.Mask" "F.Paste")
			(net 366 "/PD and TB DC-DC/USB3.D_A_N")
			(pinfunction "C_USB_TN")
			(pintype "bidirectional")
			(solder_paste_margin_ratio 0)
		)
		(pad "L7" smd oval
			(at 0.5 2.5 270)
			(size 0.17 0.25)
			(layers "F.Cu" "F.Mask" "F.Paste")
			(net 367 "/PD and TB DC-DC/USB3.D_B_N")
			(pinfunction "C_USB_BN")
			(pintype "bidirectional")
			(solder_paste_margin_ratio 0)
		)
		(pad "L8" smd oval
			(at 1 2.5 270)
			(size 0.17 0.25)
			(layers "F.Cu" "F.Mask" "F.Paste")
			(net 361 "/PD and TB DC-DC/USB3.SBU2")
			(pinfunction "C_SBU2")
			(pintype "bidirectional")
			(solder_paste_margin_ratio 0)
		)
		(pad "L9" smd oval
			(at 1.5 2.5 270)
			(size 0.17 0.25)
			(layers "F.Cu" "F.Mask" "F.Paste")
			(net 306 "/PD and TB DC-DC/USB3.CC1")
			(pinfunction "C_CC1")
			(pintype "bidirectional")
			(solder_paste_margin_ratio 0)
		)
		(pad "L10" smd oval
			(at 2 2.5 270)
			(size 0.17 0.25)
			(layers "F.Cu" "F.Mask" "F.Paste")
			(net 305 "/PD and TB DC-DC/USB3.CC2")
			(pinfunction "C_CC2")
			(pintype "bidirectional")
			(solder_paste_margin_ratio 0)
		)
		(pad "L11" smd circle
			(at 2.5 2.5 180)
			(size 0.25 0.25)
			(layers "F.Cu" "F.Mask")
			(net 301 "unconnected-(U3-NC-PadL11)")
			(pinfunction "NC")
			(pintype "no_connect")
			(solder_paste_margin_ratio 0)
		)
	)
)
